# BASEBOARD_FAB2 (Tioga Pass) — schematic netlist excerpt (pin names and nets, part order shuffled) for the footprints in the layout excerpt that follows; sources: Cadence DE-HDL packaged netlist, KiCad conversion of Wiwynn_Tioga_Pass_MB.brd

CT70  CAP_A  0.1UF 16V 10% X7R  pkg 0402V  page 212 : A = VR_PVCCIO_CPU0_AIREF1 ; B = GND
C1F7  CAPP  470UF 16V 20% ALUM  pkg 4040LF  page 195 : A = P12V_STBY ; B = GND

(kicad_pcb
	(version 20260206)
	(generator "pcbnew")
	(generator_version "10.0")
	(general
		(thickness 1.6)
		(legacy_teardrops no)
	)
	(paper "A4")
	(title_block
		(title "Wiwynn_Tioga_Pass_MB.brd")
		(comment 1 "Tioga Pass / footprints 1543-1544 of 4770")
	)
	(layers
		(0 "F.Cu" signal "TOP")
		(4 "In1.Cu" signal "L2GND")
		(6 "In2.Cu" signal "L3")
		(8 "In3.Cu" signal "L4GND")
		(10 "In4.Cu" signal "L5")
		(12 "In5.Cu" signal "L6GND")
		(14 "In6.Cu" signal "L7VCC")
		(16 "In7.Cu" signal "L8VCC")
		(18 "In8.Cu" signal "L9GND")
		(20 "In9.Cu" signal "L10")
		(22 "In10.Cu" signal "L11GND")
		(24 "In11.Cu" signal "L12")
		(26 "In12.Cu" signal "L13GND")
		(2 "B.Cu" signal "BOTTOM")
		(9 "F.Adhes" user "F.Adhesive")
		(11 "B.Adhes" user "B.Adhesive")
		(13 "F.Paste" user "Package Geometry/Pastemask Top")
		(15 "B.Paste" user "Package Geometry/Pastemask Bottom")
		(5 "F.SilkS" user "Ref Des/Silkscreen Top")
		(7 "B.SilkS" user "Ref Des/Silkscreen Bottom")
		(1 "F.Mask" user "Board Geometry/Soldermask Top")
		(3 "B.Mask" user "Board Geometry/Soldermask Bottom")
		(17 "Dwgs.User" user "User.Drawings")
		(19 "Cmts.User" user "User.Comments")
		(21 "Eco1.User" user "User.Eco1")
		(23 "Eco2.User" user "User.Eco2")
		(25 "Edge.Cuts" user "Board Geometry/Outline")
		(27 "Margin" user)
		(31 "F.CrtYd" user "Package Geometry/Place Bound Top")
		(29 "B.CrtYd" user "Package Geometry/Place Bound Bottom")
		(35 "F.Fab" user "Ref Des/Assembly Top")
		(33 "B.Fab" user "Ref Des/Assembly Bottom")
	)
	(footprint ""
		(layer "F.Cu")
		(at 352.7298 -100.29063 90)
		(property "Reference" "CT70"
			(at 0.86233 -0.5842 0)
			(unlocked yes)
			(layer "F.SilkS")
			(effects
				(font
					(size 0.7874 0.5842)
					(thickness 0.1524)
				)
				(justify left)
			)
		)
		(property "Value" ""
			(at 0 0 90)
			(layer "F.Fab")
			(effects
				(font
					(size 1.27 1.27)
				)
			)
		)
		(duplicate_pad_numbers_are_jumpers no)
		(fp_poly
			(pts
				(xy 0.3048 -0.1016) (xy 0.3048 0.9906) (xy -0.3048 0.9906) (xy -0.3048 -0.1016)
			)
			(stroke
				(width 0)
				(type default)
			)
			(fill no)
			(layer "F.CrtYd")
		)
		(fp_line
			(start 0.3048 -0.1016)
			(end -0.3048 -0.1016)
			(stroke
				(width 0.1)
				(type default)
			)
			(layer "F.Fab")
		)
		(fp_line
			(start -0.3048 -0.1016)
			(end -0.3048 0.9906)
			(stroke
				(width 0.1)
				(type default)
			)
			(layer "F.Fab")
		)
		(fp_line
			(start 0.3048 0.9906)
			(end 0.3048 -0.1016)
			(stroke
				(width 0.1)
				(type default)
			)
			(layer "F.Fab")
		)
		(fp_line
			(start -0.3048 0.9906)
			(end 0.3048 0.9906)
			(stroke
				(width 0.1)
				(type default)
			)
			(layer "F.Fab")
		)
		(pad "1" smd rect
			(at 0 0 90)
			(size 0.508 0.508)
			(layers "F.Cu" "F.Mask" "F.Paste")
			(net "VR_PVCCIO_CPU0_AIREF1")
		)
		(pad "2" smd rect
			(at 0 0.889 90)
			(size 0.508 0.508)
			(layers "F.Cu" "F.Mask" "F.Paste")
			(net "GND")
		)
		(zone
			(layer "F.Cu")
			(hatch none 0.5)
			(connect_pads
				(clearance 0)
			)
			(min_thickness 0.25)
			(keepout
				(tracks allowed)
				(vias not_allowed)
				(pads allowed)
				(copperpour not_allowed)
				(footprints allowed)
			)
			(placement
				(enabled no)
				(sheetname "")
			)
			(fill
				(thermal_gap 0.5)
				(thermal_bridge_width 0.5)
				(island_removal_mode 0)
			)
			(polygon
				(pts
					(xy 352.9838 -100.03663) (xy 352.9838 -100.54463) (xy 353.3648 -100.54463) (xy 353.3648 -100.03663)
				)
			)
		)
		(zone
			(layer "F.Cu")
			(hatch none 0.5)
			(connect_pads
				(clearance 0)
			)
			(min_thickness 0.25)
			(keepout
				(tracks not_allowed)
				(vias allowed)
				(pads allowed)
				(copperpour not_allowed)
				(footprints allowed)
			)
			(placement
				(enabled no)
				(sheetname "")
			)
			(fill
				(thermal_gap 0.5)
				(thermal_bridge_width 0.5)
				(island_removal_mode 0)
			)
			(polygon
				(pts
					(xy 353.3648 -100.03663) (xy 353.3648 -100.54463) (xy 352.9838 -100.54463) (xy 352.9838 -100.03663)
				)
			)
		)
	)
	(footprint ""
		(layer "F.Cu")
		(at 43.311064 -38.008306 180)
		(property "Reference" "C1F7"
			(at 6.17347 4.1656 270)
			(unlocked yes)
			(layer "F.SilkS")
			(effects
				(font
					(size 0.7874 0.5842)
					(thickness 0.1524)
				)
			)
		)
		(property "Value" ""
			(at 0 0 180)
			(layer "F.Fab")
			(effects
				(font
					(size 1.27 1.27)
				)
			)
		)
		(duplicate_pad_numbers_are_jumpers no)
		(fp_line
			(start 5.1435 9.271)
			(end 1.4097 9.271)
			(stroke
				(width 0.1524)
				(type default)
			)
			(layer "F.SilkS")
		)
		(fp_line
			(start 5.1435 -0.127)
			(end 5.1435 9.271)
			(stroke
				(width 0.1524)
				(type default)
			)
			(layer "F.SilkS")
		)
		(fp_line
			(start 4.3815 -1.016)
			(end 5.1435 -0.127)
			(stroke
				(width 0.1524)
				(type default)
			)
			(layer "F.SilkS")
		)
		(fp_line
			(start 1.8415 2.0955)
			(end 1.4097 2.0955)
			(stroke
				(width 0.1524)
				(type default)
			)
			(layer "F.SilkS")
		)
		(fp_line
			(start 1.8415 -1.016)
			(end 4.3815 -1.016)
			(stroke
				(width 0.1524)
				(type default)
			)
			(layer "F.SilkS")
		)
		(fp_line
			(start 1.8415 -2.0955)
			(end 1.8415 2.0955)
			(stroke
				(width 0.1524)
				(type default)
			)
			(layer "F.SilkS")
		)
		(fp_line
			(start 1.4097 -2.0955)
			(end 1.8415 -2.0955)
			(stroke
				(width 0.1524)
				(type default)
			)
			(layer "F.SilkS")
		)
		(fp_line
			(start -1.4097 9.271)
			(end -5.1435 9.271)
			(stroke
				(width 0.1524)
				(type default)
			)
			(layer "F.SilkS")
		)
		(fp_line
			(start -1.4097 -2.0955)
			(end -1.8415 -2.0955)
			(stroke
				(width 0.1524)
				(type default)
			)
			(layer "F.SilkS")
		)
		(fp_line
			(start -1.8415 2.0955)
			(end -1.4097 2.0955)
			(stroke
				(width 0.1524)
				(type default)
			)
			(layer "F.SilkS")
		)
		(fp_line
			(start -1.8415 -2.0955)
			(end -1.8415 2.0955)
			(stroke
				(width 0.1524)
				(type default)
			)
			(layer "F.SilkS")
		)
		(fp_line
			(start -4.3815 -1.016)
			(end -1.8415 -1.016)
			(stroke
				(width 0.1524)
				(type default)
			)
			(layer "F.SilkS")
		)
		(fp_line
			(start -5.1435 9.271)
			(end -5.1435 -0.127)
			(stroke
				(width 0.1524)
				(type default)
			)
			(layer "F.SilkS")
		)
		(fp_line
			(start -5.1435 -0.127)
			(end -4.3815 -1.016)
			(stroke
				(width 0.1524)
				(type default)
			)
			(layer "F.SilkS")
		)
		(fp_poly
			(pts
				(xy -5.14604 -0.12954) (xy -4.38404 -1.01346) (xy 4.37896 -1.016) (xy 5.1435 -0.12954) (xy 5.14096 9.271)
				(xy -5.14604 9.27354)
			)
			(stroke
				(width 0)
				(type default)
			)
			(fill no)
			(layer "F.CrtYd")
		)
		(fp_line
			(start 5.1435 9.271)
			(end -5.1435 9.271)
			(stroke
				(width 0.1)
				(type default)
			)
			(layer "F.Fab")
		)
		(fp_line
			(start 5.1435 -0.127)
			(end 5.1435 9.271)
			(stroke
				(width 0.1)
				(type default)
			)
			(layer "F.Fab")
		)
		(fp_line
			(start 4.3815 -1.016)
			(end 5.1435 -0.127)
			(stroke
				(width 0.1)
				(type default)
			)
			(layer "F.Fab")
		)
		(fp_line
			(start -4.3815 -1.016)
			(end 4.3815 -1.016)
			(stroke
				(width 0.1)
				(type default)
			)
			(layer "F.Fab")
		)
		(fp_line
			(start -5.1435 9.271)
			(end -5.1435 -0.127)
			(stroke
				(width 0.1)
				(type default)
			)
			(layer "F.Fab")
		)
		(fp_line
			(start -5.1435 -0.127)
			(end -4.3815 -1.016)
			(stroke
				(width 0.1)
				(type default)
			)
			(layer "F.Fab")
		)
		(fp_circle
			(center 0 4.1275)
			(end -4.9911 4.1275)
			(stroke
				(width 0.1)
				(type default)
			)
			(fill no)
			(layer "F.Fab")
		)
		(pad "1" smd rect
			(at 0 0 180)
			(size 1.905 4.191)
			(layers "F.Cu" "F.Mask" "F.Paste")
			(net "P12V_STBY")
		)
		(pad "2" smd rect
			(at 0 8.255 180)
			(size 1.905 4.191)
			(layers "F.Cu" "F.Mask" "F.Paste")
			(net "GND")
		)
		(zone
			(layer "F.Cu")
			(hatch none 0.5)
			(connect_pads
				(clearance 0)
			)
			(min_thickness 0.25)
			(keepout
				(tracks allowed)
				(vias not_allowed)
				(pads allowed)
				(copperpour not_allowed)
				(footprints allowed)
			)
			(placement
				(enabled no)
				(sheetname "")
			)
			(fill
				(thermal_gap 0.5)
				(thermal_bridge_width 0.5)
				(island_removal_mode 0)
			)
			(polygon
				(pts
					(xy 48.454564 -47.279306) (xy 38.167564 -47.279306) (xy 38.167564 -37.881306) (xy 38.929564 -36.992306)
					(xy 47.692564 -36.992306) (xy 48.454564 -37.881306)
				)
			)
		)
	)
)
